# T6G (Grand Teton) — schematic netlist excerpt (pin names and nets, part order shuffled) for the footprints in the layout excerpt that follows; sources: Cadence DE-HDL packaged netlist, KiCad conversion of 04192023_DAF0TMB3IC0_F0TG_MB_C_brd_V02_OCP.brd

R342  Q_RES  51 5% EMPTY  pkg 0402LF  page 180 : A = USB3_CPU0_BMC_TX_DN ; B = GND
R6853  Q_RES  0 5% CHIP  pkg 0402LF  page 81 : A = PWRGD_P0V9_RETIMER_CPU1 ; B = PWRGD_P0V9_RETIMER_CPU1_R2

(kicad_pcb
	(version 20260206)
	(generator "pcbnew")
	(generator_version "10.0")
	(general
		(thickness 1.6)
		(legacy_teardrops no)
	)
	(paper "A4")
	(title_block
		(title "04192023_DAF0TMB3IC0_F0TG_MB_C_brd_V02_OCP.brd")
		(comment 1 "Grand Teton / footprints 47-48 of 8354")
	)
	(layers
		(0 "F.Cu" signal "TOP")
		(4 "In1.Cu" signal "GND")
		(6 "In2.Cu" signal "IN1")
		(8 "In3.Cu" signal "GND1")
		(10 "In4.Cu" signal "IN2")
		(12 "In5.Cu" signal "GND2")
		(14 "In6.Cu" signal "IN3")
		(16 "In7.Cu" signal "GND3")
		(18 "In8.Cu" signal "VCC")
		(20 "In9.Cu" signal "VCC1")
		(22 "In10.Cu" signal "GND4")
		(24 "In11.Cu" signal "IN4")
		(26 "In12.Cu" signal "GND5")
		(28 "In13.Cu" signal "IN5")
		(30 "In14.Cu" signal "GND6")
		(32 "In15.Cu" signal "IN6")
		(34 "In16.Cu" signal "GND7")
		(2 "B.Cu" signal "BOTTOM")
		(9 "F.Adhes" user "F.Adhesive")
		(11 "B.Adhes" user "B.Adhesive")
		(13 "F.Paste" user "Package Geometry/Pastemask Top")
		(15 "B.Paste" user "Package Geometry/Pastemask Bottom")
		(5 "F.SilkS" user "Ref Des/Silkscreen Top")
		(7 "B.SilkS" user "Ref Des/Silkscreen Bottom")
		(1 "F.Mask" user "Board Geometry/Soldermask Top")
		(3 "B.Mask" user "Board Geometry/Soldermask Bottom")
		(17 "Dwgs.User" user "User.Drawings")
		(19 "Cmts.User" user "User.Comments")
		(21 "Eco1.User" user "User.Eco1")
		(23 "Eco2.User" user "User.Eco2")
		(25 "Edge.Cuts" user "Board Geometry/Outline")
		(27 "Margin" user)
		(31 "F.CrtYd" user "Package Geometry/Place Bound Top")
		(29 "B.CrtYd" user "Package Geometry/Place Bound Bottom")
		(35 "F.Fab" user "Ref Des/Assembly Top")
		(33 "B.Fab" user "Ref Des/Assembly Bottom")
	)
	(footprint ""
		(layer "F.Cu")
		(at 176.855882 -137.740898 -90)
		(property "Reference" "R6853"
			(at 0 0 270)
			(layer "F.SilkS")
			(hide yes)
			(effects
				(font
					(size 1.27 1.27)
				)
			)
		)
		(property "Value" ""
			(at 0 0 270)
			(layer "F.Fab")
			(effects
				(font
					(size 1.27 1.27)
				)
			)
		)
		(duplicate_pad_numbers_are_jumpers no)
		(fp_line
			(start -0.7874 0.4064)
			(end -0.7874 -0.4064)
			(stroke
				(width 0.1524)
				(type default)
			)
			(layer "F.SilkS")
		)
		(fp_line
			(start 0.7874 0.4064)
			(end -0.7874 0.4064)
			(stroke
				(width 0.1524)
				(type default)
			)
			(layer "F.SilkS")
		)
		(fp_line
			(start -0.7874 -0.4064)
			(end 0.7874 -0.4064)
			(stroke
				(width 0.1524)
				(type default)
			)
			(layer "F.SilkS")
		)
		(fp_line
			(start 0.7874 -0.4064)
			(end 0.7874 0.4064)
			(stroke
				(width 0.1524)
				(type default)
			)
			(layer "F.SilkS")
		)
		(fp_line
			(start -0.67945 0.3048)
			(end -0.67945 -0.305054)
			(stroke
				(width 0.1)
				(type default)
			)
			(layer "F.Fab")
		)
		(fp_line
			(start -0.12065 0.3048)
			(end -0.67945 0.3048)
			(stroke
				(width 0.1)
				(type default)
			)
			(layer "F.Fab")
		)
		(fp_line
			(start 0.120396 0.3048)
			(end 0.120396 0.2794)
			(stroke
				(width 0.1)
				(type default)
			)
			(layer "F.Fab")
		)
		(fp_line
			(start 0.67945 0.3048)
			(end 0.120396 0.3048)
			(stroke
				(width 0.1)
				(type default)
			)
			(layer "F.Fab")
		)
		(fp_line
			(start -0.12065 0.2794)
			(end -0.12065 0.3048)
			(stroke
				(width 0.1)
				(type default)
			)
			(layer "F.Fab")
		)
		(fp_line
			(start 0.120396 0.2794)
			(end -0.12065 0.2794)
			(stroke
				(width 0.1)
				(type default)
			)
			(layer "F.Fab")
		)
		(fp_line
			(start -0.12065 -0.2794)
			(end 0.12065 -0.2794)
			(stroke
				(width 0.1)
				(type default)
			)
			(layer "F.Fab")
		)
		(fp_line
			(start 0.12065 -0.2794)
			(end 0.12065 -0.3048)
			(stroke
				(width 0.1)
				(type default)
			)
			(layer "F.Fab")
		)
		(fp_line
			(start 0.12065 -0.3048)
			(end 0.67945 -0.3048)
			(stroke
				(width 0.1)
				(type default)
			)
			(layer "F.Fab")
		)
		(fp_line
			(start 0.67945 -0.3048)
			(end 0.67945 0.3048)
			(stroke
				(width 0.1)
				(type default)
			)
			(layer "F.Fab")
		)
		(fp_line
			(start -0.67945 -0.305054)
			(end -0.12065 -0.305054)
			(stroke
				(width 0.1)
				(type default)
			)
			(layer "F.Fab")
		)
		(fp_line
			(start -0.12065 -0.305054)
			(end -0.12065 -0.2794)
			(stroke
				(width 0.1)
				(type default)
			)
			(layer "F.Fab")
		)
		(pad "1" smd circle
			(at -0.40005 0 270)
			(size 0 0)
			(layers "F.Cu" "F.Mask" "F.Paste")
			(net "PWRGD_P0V9_RETIMER_CPU1")
		)
		(pad "2" smd circle
			(at 0.40005 0 270)
			(size 0 0)
			(layers "F.Cu" "F.Mask" "F.Paste")
			(net "PWRGD_P0V9_RETIMER_CPU1_R2")
		)
	)
	(footprint ""
		(layer "F.Cu")
		(at 143.96339 -31.18739 180)
		(property "Reference" "R342"
			(at 0 0 180)
			(layer "F.SilkS")
			(hide yes)
			(effects
				(font
					(size 1.27 1.27)
				)
			)
		)
		(property "Value" ""
			(at 0 0 180)
			(layer "F.Fab")
			(effects
				(font
					(size 1.27 1.27)
				)
			)
		)
		(duplicate_pad_numbers_are_jumpers no)
		(fp_line
			(start 0.7874 0.4064)
			(end -0.7874 0.4064)
			(stroke
				(width 0.1524)
				(type default)
			)
			(layer "F.SilkS")
		)
		(fp_line
			(start 0.7874 -0.4064)
			(end 0.7874 0.4064)
			(stroke
				(width 0.1524)
				(type default)
			)
			(layer "F.SilkS")
		)
		(fp_line
			(start -0.7874 0.4064)
			(end -0.7874 -0.4064)
			(stroke
				(width 0.1524)
				(type default)
			)
			(layer "F.SilkS")
		)
		(fp_line
			(start -0.7874 -0.4064)
			(end 0.7874 -0.4064)
			(stroke
				(width 0.1524)
				(type default)
			)
			(layer "F.SilkS")
		)
		(fp_line
			(start 0.67945 0.3048)
			(end 0.120396 0.3048)
			(stroke
				(width 0.1)
				(type default)
			)
			(layer "F.Fab")
		)
		(fp_line
			(start 0.67945 -0.3048)
			(end 0.67945 0.3048)
			(stroke
				(width 0.1)
				(type default)
			)
			(layer "F.Fab")
		)
		(fp_line
			(start 0.12065 -0.2794)
			(end 0.12065 -0.3048)
			(stroke
				(width 0.1)
				(type default)
			)
			(layer "F.Fab")
		)
		(fp_line
			(start 0.12065 -0.3048)
			(end 0.67945 -0.3048)
			(stroke
				(width 0.1)
				(type default)
			)
			(layer "F.Fab")
		)
		(fp_line
			(start 0.120396 0.3048)
			(end 0.120396 0.2794)
			(stroke
				(width 0.1)
				(type default)
			)
			(layer "F.Fab")
		)
		(fp_line
			(start 0.120396 0.2794)
			(end -0.12065 0.2794)
			(stroke
				(width 0.1)
				(type default)
			)
			(layer "F.Fab")
		)
		(fp_line
			(start -0.12065 0.3048)
			(end -0.67945 0.3048)
			(stroke
				(width 0.1)
				(type default)
			)
			(layer "F.Fab")
		)
		(fp_line
			(start -0.12065 0.2794)
			(end -0.12065 0.3048)
			(stroke
				(width 0.1)
				(type default)
			)
			(layer "F.Fab")
		)
		(fp_line
			(start -0.12065 -0.2794)
			(end 0.12065 -0.2794)
			(stroke
				(width 0.1)
				(type default)
			)
			(layer "F.Fab")
		)
		(fp_line
			(start -0.12065 -0.305054)
			(end -0.12065 -0.2794)
			(stroke
				(width 0.1)
				(type default)
			)
			(layer "F.Fab")
		)
		(fp_line
			(start -0.67945 0.3048)
			(end -0.67945 -0.305054)
			(stroke
				(width 0.1)
				(type default)
			)
			(layer "F.Fab")
		)
		(fp_line
			(start -0.67945 -0.305054)
			(end -0.12065 -0.305054)
			(stroke
				(width 0.1)
				(type default)
			)
			(layer "F.Fab")
		)
		(pad "1" smd rect
			(at -0.40005 0)
			(size 0.4572 0.508)
			(layers "F.Cu" "F.Mask" "F.Paste")
			(net "USB3_CPU0_BMC_TX_DN")
		)
		(pad "2" smd rect
			(at 0.40005 0)
			(size 0.4572 0.508)
			(layers "F.Cu" "F.Mask" "F.Paste")
			(net "GND")
		)
	)
)
